# S9S_MB_2U (Grand Teton) — schematic netlist excerpt (pin names and nets, part order shuffled) for the footprints in the layout excerpt that follows; sources: Cadence DE-HDL packaged netlist, KiCad conversion of 03242023_DA0F0TMBIJ0_F0T_Motherboard_J_brd_V01_OCP.brd

R2979  Q_RES  10K 1% EMPTY  pkg 0402LF  page 195 : A = P1V05_PCH_AUX ; B = FM_BOARD_SKU_ID2
PR568  Q_RES  100 1% CHIP  pkg 0402LF  page 292 : A = VSENSE_PVCCINFAON_CPU1_DP ; B = PVCCINFAON_CPU1

(kicad_pcb
	(version 20260206)
	(generator "pcbnew")
	(generator_version "10.0")
	(general
		(thickness 1.6)
		(legacy_teardrops no)
	)
	(paper "A4")
	(title_block
		(title "03242023_DA0F0TMBIJ0_F0T_Motherboard_J_brd_V01_OCP.brd")
		(comment 1 "Grand Teton / footprints 1912-1913 of 6105")
	)
	(layers
		(0 "F.Cu" signal "TOP")
		(4 "In1.Cu" signal "GND")
		(6 "In2.Cu" signal "IN1")
		(8 "In3.Cu" signal "GND1")
		(10 "In4.Cu" signal "IN2")
		(12 "In5.Cu" signal "GND2")
		(14 "In6.Cu" signal "IN3")
		(16 "In7.Cu" signal "GND3")
		(18 "In8.Cu" signal "VCC")
		(20 "In9.Cu" signal "VCC1")
		(22 "In10.Cu" signal "GND4")
		(24 "In11.Cu" signal "IN4")
		(26 "In12.Cu" signal "GND5")
		(28 "In13.Cu" signal "IN5")
		(30 "In14.Cu" signal "GND6")
		(32 "In15.Cu" signal "IN6")
		(34 "In16.Cu" signal "GND7")
		(2 "B.Cu" signal "BOTTOM")
		(9 "F.Adhes" user "F.Adhesive")
		(11 "B.Adhes" user "B.Adhesive")
		(13 "F.Paste" user "Package Geometry/Pastemask Top")
		(15 "B.Paste" user "Package Geometry/Pastemask Bottom")
		(5 "F.SilkS" user "Ref Des/Silkscreen Top")
		(7 "B.SilkS" user "Ref Des/Silkscreen Bottom")
		(1 "F.Mask" user "Board Geometry/Soldermask Top")
		(3 "B.Mask" user "Board Geometry/Soldermask Bottom")
		(17 "Dwgs.User" user "User.Drawings")
		(19 "Cmts.User" user "User.Comments")
		(21 "Eco1.User" user "User.Eco1")
		(23 "Eco2.User" user "User.Eco2")
		(25 "Edge.Cuts" user "Board Geometry/Outline")
		(27 "Margin" user)
		(31 "F.CrtYd" user "Package Geometry/Place Bound Top")
		(29 "B.CrtYd" user "Package Geometry/Place Bound Bottom")
		(35 "F.Fab" user "Ref Des/Assembly Top")
		(33 "B.Fab" user "Ref Des/Assembly Bottom")
	)
	(footprint ""
		(layer "F.Cu")
		(at 73.28408 -143.769588 180)
		(property "Reference" "PR568"
			(at 0 0 180)
			(layer "F.SilkS")
			(hide yes)
			(effects
				(font
					(size 1.27 1.27)
				)
			)
		)
		(property "Value" ""
			(at 0 0 180)
			(layer "F.Fab")
			(effects
				(font
					(size 1.27 1.27)
				)
			)
		)
		(duplicate_pad_numbers_are_jumpers no)
		(fp_line
			(start 0.7874 0.4064)
			(end -0.7874 0.4064)
			(stroke
				(width 0.1524)
				(type default)
			)
			(layer "F.SilkS")
		)
		(fp_line
			(start 0.7874 -0.4064)
			(end 0.7874 0.4064)
			(stroke
				(width 0.1524)
				(type default)
			)
			(layer "F.SilkS")
		)
		(fp_line
			(start -0.7874 0.4064)
			(end -0.7874 -0.4064)
			(stroke
				(width 0.1524)
				(type default)
			)
			(layer "F.SilkS")
		)
		(fp_line
			(start -0.7874 -0.4064)
			(end 0.7874 -0.4064)
			(stroke
				(width 0.1524)
				(type default)
			)
			(layer "F.SilkS")
		)
		(fp_line
			(start 0.67945 0.3048)
			(end 0.120396 0.3048)
			(stroke
				(width 0.1)
				(type default)
			)
			(layer "F.Fab")
		)
		(fp_line
			(start 0.67945 -0.3048)
			(end 0.67945 0.3048)
			(stroke
				(width 0.1)
				(type default)
			)
			(layer "F.Fab")
		)
		(fp_line
			(start 0.12065 -0.2794)
			(end 0.12065 -0.3048)
			(stroke
				(width 0.1)
				(type default)
			)
			(layer "F.Fab")
		)
		(fp_line
			(start 0.12065 -0.3048)
			(end 0.67945 -0.3048)
			(stroke
				(width 0.1)
				(type default)
			)
			(layer "F.Fab")
		)
		(fp_line
			(start 0.120396 0.3048)
			(end 0.120396 0.2794)
			(stroke
				(width 0.1)
				(type default)
			)
			(layer "F.Fab")
		)
		(fp_line
			(start 0.120396 0.2794)
			(end -0.12065 0.2794)
			(stroke
				(width 0.1)
				(type default)
			)
			(layer "F.Fab")
		)
		(fp_line
			(start -0.12065 0.3048)
			(end -0.67945 0.3048)
			(stroke
				(width 0.1)
				(type default)
			)
			(layer "F.Fab")
		)
		(fp_line
			(start -0.12065 0.2794)
			(end -0.12065 0.3048)
			(stroke
				(width 0.1)
				(type default)
			)
			(layer "F.Fab")
		)
		(fp_line
			(start -0.12065 -0.2794)
			(end 0.12065 -0.2794)
			(stroke
				(width 0.1)
				(type default)
			)
			(layer "F.Fab")
		)
		(fp_line
			(start -0.12065 -0.305054)
			(end -0.12065 -0.2794)
			(stroke
				(width 0.1)
				(type default)
			)
			(layer "F.Fab")
		)
		(fp_line
			(start -0.67945 0.3048)
			(end -0.67945 -0.305054)
			(stroke
				(width 0.1)
				(type default)
			)
			(layer "F.Fab")
		)
		(fp_line
			(start -0.67945 -0.305054)
			(end -0.12065 -0.305054)
			(stroke
				(width 0.1)
				(type default)
			)
			(layer "F.Fab")
		)
		(pad "1" smd circle
			(at -0.40005 0 180)
			(size 0 0)
			(layers "F.Cu" "F.Mask" "F.Paste")
			(net "VSENSE_PVCCINFAON_CPU1_DP")
		)
		(pad "2" smd circle
			(at 0.40005 0 180)
			(size 0 0)
			(layers "F.Cu" "F.Mask" "F.Paste")
			(net "PVCCINFAON_CPU1")
		)
	)
	(footprint ""
		(layer "F.Cu")
		(at 299.02023 -55.416196)
		(property "Reference" "R2979"
			(at 0 0 0)
			(layer "F.SilkS")
			(hide yes)
			(effects
				(font
					(size 1.27 1.27)
				)
			)
		)
		(property "Value" ""
			(at 0 0 0)
			(layer "F.Fab")
			(effects
				(font
					(size 1.27 1.27)
				)
			)
		)
		(duplicate_pad_numbers_are_jumpers no)
		(fp_line
			(start -0.7874 -0.4064)
			(end 0.7874 -0.4064)
			(stroke
				(width 0.1524)
				(type default)
			)
			(layer "F.SilkS")
		)
		(fp_line
			(start -0.7874 0.4064)
			(end -0.7874 -0.4064)
			(stroke
				(width 0.1524)
				(type default)
			)
			(layer "F.SilkS")
		)
		(fp_line
			(start 0.7874 -0.4064)
			(end 0.7874 0.4064)
			(stroke
				(width 0.1524)
				(type default)
			)
			(layer "F.SilkS")
		)
		(fp_line
			(start 0.7874 0.4064)
			(end -0.7874 0.4064)
			(stroke
				(width 0.1524)
				(type default)
			)
			(layer "F.SilkS")
		)
		(fp_line
			(start -0.67945 -0.305054)
			(end -0.12065 -0.305054)
			(stroke
				(width 0.1)
				(type default)
			)
			(layer "F.Fab")
		)
		(fp_line
			(start -0.67945 0.3048)
			(end -0.67945 -0.305054)
			(stroke
				(width 0.1)
				(type default)
			)
			(layer "F.Fab")
		)
		(fp_line
			(start -0.12065 -0.305054)
			(end -0.12065 -0.2794)
			(stroke
				(width 0.1)
				(type default)
			)
			(layer "F.Fab")
		)
		(fp_line
			(start -0.12065 -0.2794)
			(end 0.12065 -0.2794)
			(stroke
				(width 0.1)
				(type default)
			)
			(layer "F.Fab")
		)
		(fp_line
			(start -0.12065 0.2794)
			(end -0.12065 0.3048)
			(stroke
				(width 0.1)
				(type default)
			)
			(layer "F.Fab")
		)
		(fp_line
			(start -0.12065 0.3048)
			(end -0.67945 0.3048)
			(stroke
				(width 0.1)
				(type default)
			)
			(layer "F.Fab")
		)
		(fp_line
			(start 0.120396 0.2794)
			(end -0.12065 0.2794)
			(stroke
				(width 0.1)
				(type default)
			)
			(layer "F.Fab")
		)
		(fp_line
			(start 0.120396 0.3048)
			(end 0.120396 0.2794)
			(stroke
				(width 0.1)
				(type default)
			)
			(layer "F.Fab")
		)
		(fp_line
			(start 0.12065 -0.3048)
			(end 0.67945 -0.3048)
			(stroke
				(width 0.1)
				(type default)
			)
			(layer "F.Fab")
		)
		(fp_line
			(start 0.12065 -0.2794)
			(end 0.12065 -0.3048)
			(stroke
				(width 0.1)
				(type default)
			)
			(layer "F.Fab")
		)
		(fp_line
			(start 0.67945 -0.3048)
			(end 0.67945 0.3048)
			(stroke
				(width 0.1)
				(type default)
			)
			(layer "F.Fab")
		)
		(fp_line
			(start 0.67945 0.3048)
			(end 0.120396 0.3048)
			(stroke
				(width 0.1)
				(type default)
			)
			(layer "F.Fab")
		)
		(pad "1" smd circle
			(at -0.40005 0)
			(size 0 0)
			(layers "F.Cu" "F.Mask" "F.Paste")
			(net "P1V05_PCH_AUX")
		)
		(pad "2" smd circle
			(at 0.40005 0)
			(size 0 0)
			(layers "F.Cu" "F.Mask" "F.Paste")
			(net "FM_BOARD_SKU_ID2")
		)
	)
)
